(kicad_pcb
	(version 20260206)
	(generator "pcbnew")
	(generator_version "10.0")
	(general
		(thickness 1.6)
		(legacy_teardrops no)
	)
	(paper "A4")
	(title_block
		(title "9054_F0T_PDB_BD_GPU_F_V04_1213_1550_OCP.brd")
		(comment 1 "Grand Teton / footprints 235-240 of 608")
	)
	(layers
		(0 "F.Cu" signal "TOP")
		(4 "In1.Cu" signal "GND")
		(6 "In2.Cu" signal "IN1")
		(8 "In3.Cu" signal "GND1")
		(10 "In4.Cu" signal "VCC")
		(12 "In5.Cu" signal "VCC1")
		(14 "In6.Cu" signal "GND2")
		(16 "In7.Cu" signal "IN2")
		(18 "In8.Cu" signal "GND3")
		(2 "B.Cu" signal "BOTTOM")
		(9 "F.Adhes" user "F.Adhesive")
		(11 "B.Adhes" user "B.Adhesive")
		(13 "F.Paste" user "Package Geometry/Pastemask Top")
		(15 "B.Paste" user "Package Geometry/Pastemask Bottom")
		(5 "F.SilkS" user "Ref Des/Silkscreen Top")
		(7 "B.SilkS" user "Ref Des/Silkscreen Bottom")
		(1 "F.Mask" user "Board Geometry/Soldermask Top")
		(3 "B.Mask" user "Board Geometry/Soldermask Bottom")
		(17 "Dwgs.User" user "User.Drawings")
		(19 "Cmts.User" user "User.Comments")
		(21 "Eco1.User" user "User.Eco1")
		(23 "Eco2.User" user "User.Eco2")
		(25 "Edge.Cuts" user "Board Geometry/Outline")
		(27 "Margin" user)
		(31 "F.CrtYd" user "Package Geometry/Place Bound Top")
		(29 "B.CrtYd" user "Package Geometry/Place Bound Bottom")
		(35 "F.Fab" user "Ref Des/Assembly Top")
		(33 "B.Fab" user "Ref Des/Assembly Bottom")
	)
	(footprint ""
		(layer "F.Cu")
		(at 321.945 -84.709)
		(property "Reference" "PQ37"
			(at -0.4572 -2.24663 0)
			(unlocked yes)
			(layer "F.SilkS")
			(effects
				(font
					(size 0.7874 0.5842)
					(thickness 0.1524)
				)
				(justify left)
			)
		)
		(property "Value" ""
			(at 0 0 0)
			(layer "F.Fab")
			(effects
				(font
					(size 1.27 1.27)
				)
			)
		)
		(duplicate_pad_numbers_are_jumpers no)
		(fp_line
			(start -1.905 -1.651)
			(end 1.905 -1.651)
			(stroke
				(width 0.1524)
				(type default)
			)
			(layer "F.SilkS")
		)
		(fp_line
			(start -1.905 1.651)
			(end -1.905 -1.651)
			(stroke
				(width 0.1524)
				(type default)
			)
			(layer "F.SilkS")
		)
		(fp_line
			(start 1.905 -1.651)
			(end 1.905 1.651)
			(stroke
				(width 0.1524)
				(type default)
			)
			(layer "F.SilkS")
		)
		(fp_line
			(start 1.905 1.651)
			(end -1.905 1.651)
			(stroke
				(width 0.1524)
				(type default)
			)
			(layer "F.SilkS")
		)
		(fp_line
			(start -1.249934 -1.169924)
			(end -0.649986 -1.169924)
			(stroke
				(width 0.1)
				(type default)
			)
			(layer "F.Fab")
		)
		(fp_line
			(start -1.249934 -0.729996)
			(end -1.249934 -1.169924)
			(stroke
				(width 0.1)
				(type default)
			)
			(layer "F.Fab")
		)
		(fp_line
			(start -1.249934 0.729996)
			(end -0.6985 0.729996)
			(stroke
				(width 0.1)
				(type default)
			)
			(layer "F.Fab")
		)
		(fp_line
			(start -1.249934 1.169924)
			(end -1.249934 0.729996)
			(stroke
				(width 0.1)
				(type default)
			)
			(layer "F.Fab")
		)
		(fp_line
			(start -0.6985 -0.729996)
			(end -1.249934 -0.729996)
			(stroke
				(width 0.1)
				(type default)
			)
			(layer "F.Fab")
		)
		(fp_line
			(start -0.6985 0.729996)
			(end -0.6985 -0.729996)
			(stroke
				(width 0.1)
				(type default)
			)
			(layer "F.Fab")
		)
		(fp_line
			(start -0.649986 -1.524)
			(end 0.6985 -1.524)
			(stroke
				(width 0.1)
				(type default)
			)
			(layer "F.Fab")
		)
		(fp_line
			(start -0.649986 -1.169924)
			(end -0.649986 -1.524)
			(stroke
				(width 0.1)
				(type default)
			)
			(layer "F.Fab")
		)
		(fp_line
			(start -0.649986 1.169924)
			(end -1.249934 1.169924)
			(stroke
				(width 0.1)
				(type default)
			)
			(layer "F.Fab")
		)
		(fp_line
			(start -0.649986 1.524)
			(end -0.649986 1.169924)
			(stroke
				(width 0.1)
				(type default)
			)
			(layer "F.Fab")
		)
		(fp_line
			(start 0.6985 -1.524)
			(end 0.6985 -0.219964)
			(stroke
				(width 0.1)
				(type default)
			)
			(layer "F.Fab")
		)
		(fp_line
			(start 0.6985 -0.219964)
			(end 1.249934 -0.219964)
			(stroke
				(width 0.1)
				(type default)
			)
			(layer "F.Fab")
		)
		(fp_line
			(start 0.6985 0.219964)
			(end 0.6985 1.524)
			(stroke
				(width 0.1)
				(type default)
			)
			(layer "F.Fab")
		)
		(fp_line
			(start 0.6985 1.524)
			(end -0.649986 1.524)
			(stroke
				(width 0.1)
				(type default)
			)
			(layer "F.Fab")
		)
		(fp_line
			(start 1.249934 -0.219964)
			(end 1.249934 0.219964)
			(stroke
				(width 0.1)
				(type default)
			)
			(layer "F.Fab")
		)
		(fp_line
			(start 1.249934 0.219964)
			(end 0.6985 0.219964)
			(stroke
				(width 0.1)
				(type default)
			)
			(layer "F.Fab")
		)
		(pad "B" smd rect
			(at -1.1176 -1.016 270)
			(size 1.016 1.27)
			(layers "F.Cu" "F.Mask" "F.Paste")
			(net "P52V_HS1_TEMP_R")
		)
		(pad "C" smd rect
			(at 1.1176 0 270)
			(size 1.016 1.27)
			(layers "F.Cu" "F.Mask" "F.Paste")
			(net "P52V_HS1_TEMP_R")
		)
		(pad "E" smd rect
			(at -1.1176 1.016 270)
			(size 1.016 1.27)
			(layers "F.Cu" "F.Mask" "F.Paste")
			(net "P52V_HS1_TEMPN_R")
		)
	)
	(footprint ""
		(layer "F.Cu")
		(at 271.2974 -78.105 180)
		(property "Reference" "PR483"
			(at 0 0 180)
			(layer "F.SilkS")
			(hide yes)
			(effects
				(font
					(size 1.27 1.27)
				)
			)
		)
		(property "Value" ""
			(at 0 0 180)
			(layer "F.Fab")
			(effects
				(font
					(size 1.27 1.27)
				)
			)
		)
		(duplicate_pad_numbers_are_jumpers no)
		(fp_line
			(start 0.7874 0.4064)
			(end -0.7874 0.4064)
			(stroke
				(width 0.1524)
				(type default)
			)
			(layer "F.SilkS")
		)
		(fp_line
			(start 0.7874 -0.4064)
			(end 0.7874 0.4064)
			(stroke
				(width 0.1524)
				(type default)
			)
			(layer "F.SilkS")
		)
		(fp_line
			(start -0.7874 0.4064)
			(end -0.7874 -0.4064)
			(stroke
				(width 0.1524)
				(type default)
			)
			(layer "F.SilkS")
		)
		(fp_line
			(start -0.7874 -0.4064)
			(end 0.7874 -0.4064)
			(stroke
				(width 0.1524)
				(type default)
			)
			(layer "F.SilkS")
		)
		(fp_line
			(start 0.67945 0.3048)
			(end 0.120396 0.3048)
			(stroke
				(width 0.1)
				(type default)
			)
			(layer "F.Fab")
		)
		(fp_line
			(start 0.67945 -0.3048)
			(end 0.67945 0.3048)
			(stroke
				(width 0.1)
				(type default)
			)
			(layer "F.Fab")
		)
		(fp_line
			(start 0.12065 -0.2794)
			(end 0.12065 -0.3048)
			(stroke
				(width 0.1)
				(type default)
			)
			(layer "F.Fab")
		)
		(fp_line
			(start 0.12065 -0.3048)
			(end 0.67945 -0.3048)
			(stroke
				(width 0.1)
				(type default)
			)
			(layer "F.Fab")
		)
		(fp_line
			(start 0.120396 0.3048)
			(end 0.120396 0.2794)
			(stroke
				(width 0.1)
				(type default)
			)
			(layer "F.Fab")
		)
		(fp_line
			(start 0.120396 0.2794)
			(end -0.12065 0.2794)
			(stroke
				(width 0.1)
				(type default)
			)
			(layer "F.Fab")
		)
		(fp_line
			(start -0.12065 0.3048)
			(end -0.67945 0.3048)
			(stroke
				(width 0.1)
				(type default)
			)
			(layer "F.Fab")
		)
		(fp_line
			(start -0.12065 0.2794)
			(end -0.12065 0.3048)
			(stroke
				(width 0.1)
				(type default)
			)
			(layer "F.Fab")
		)
		(fp_line
			(start -0.12065 -0.2794)
			(end 0.12065 -0.2794)
			(stroke
				(width 0.1)
				(type default)
			)
			(layer "F.Fab")
		)
		(fp_line
			(start -0.12065 -0.305054)
			(end -0.12065 -0.2794)
			(stroke
				(width 0.1)
				(type default)
			)
			(layer "F.Fab")
		)
		(fp_line
			(start -0.67945 0.3048)
			(end -0.67945 -0.305054)
			(stroke
				(width 0.1)
				(type default)
			)
			(layer "F.Fab")
		)
		(fp_line
			(start -0.67945 -0.305054)
			(end -0.12065 -0.305054)
			(stroke
				(width 0.1)
				(type default)
			)
			(layer "F.Fab")
		)
		(pad "1" smd circle
			(at -0.40005 0 180)
			(size 0 0)
			(layers "F.Cu" "F.Mask" "F.Paste")
			(net "P52V_HS1_UVLO_EN")
		)
		(pad "2" smd circle
			(at 0.40005 0 180)
			(size 0 0)
			(layers "F.Cu" "F.Mask" "F.Paste")
			(net "GND_FIELD_SIGNAL")
		)
	)
	(footprint ""
		(layer "F.Cu")
		(at 124.483876 -74.6506)
		(property "Reference" "PQ38"
			(at 8.913114 -3.609848 0)
			(unlocked yes)
			(layer "F.SilkS")
			(effects
				(font
					(size 0.7874 0.5842)
					(thickness 0.1524)
				)
				(justify left)
			)
		)
		(property "Value" ""
			(at 0 0 0)
			(layer "F.Fab")
			(effects
				(font
					(size 1.27 1.27)
				)
			)
		)
		(duplicate_pad_numbers_are_jumpers no)
		(fp_line
			(start -7.649972 -4.99999)
			(end -7.649972 -3.3274)
			(stroke
				(width 0.1524)
				(type default)
			)
			(layer "F.SilkS")
		)
		(fp_line
			(start -7.649972 -1.7526)
			(end -7.649972 1.7526)
			(stroke
				(width 0.1524)
				(type default)
			)
			(layer "F.SilkS")
		)
		(fp_line
			(start -7.649972 3.3274)
			(end -7.649972 4.99999)
			(stroke
				(width 0.1524)
				(type default)
			)
			(layer "F.SilkS")
		)
		(fp_line
			(start -7.649972 4.99999)
			(end 5.115814 4.99999)
			(stroke
				(width 0.1524)
				(type default)
			)
			(layer "F.SilkS")
		)
		(fp_line
			(start 5.115814 -4.99999)
			(end -7.649972 -4.99999)
			(stroke
				(width 0.1524)
				(type default)
			)
			(layer "F.SilkS")
		)
		(fp_line
			(start 7.630414 4.99999)
			(end 7.649972 4.99999)
			(stroke
				(width 0.1524)
				(type default)
			)
			(layer "F.SilkS")
		)
		(fp_line
			(start 7.649972 -4.99999)
			(end 7.630414 -4.99999)
			(stroke
				(width 0.1524)
				(type default)
			)
			(layer "F.SilkS")
		)
		(fp_line
			(start 7.649972 4.99999)
			(end 7.649972 -4.99999)
			(stroke
				(width 0.1524)
				(type default)
			)
			(layer "F.SilkS")
		)
		(fp_line
			(start -7.649972 -4.99999)
			(end -7.649972 4.99999)
			(stroke
				(width 0.1)
				(type default)
			)
			(layer "F.Fab")
		)
		(fp_line
			(start -7.649972 4.99999)
			(end 7.649972 4.99999)
			(stroke
				(width 0.1)
				(type default)
			)
			(layer "F.Fab")
		)
		(fp_line
			(start 7.649972 -4.99999)
			(end -7.649972 -4.99999)
			(stroke
				(width 0.1)
				(type default)
			)
			(layer "F.Fab")
		)
		(fp_line
			(start 7.649972 4.99999)
			(end 7.649972 -4.99999)
			(stroke
				(width 0.1)
				(type default)
			)
			(layer "F.Fab")
		)
		(pad "D" smd circle
			(at 2.15011 0)
			(size 0 0)
			(layers "F.Cu" "F.Mask" "F.Paste")
			(net "P52V_HS2_DRAIN_1")
		)
		(pad "G" smd rect
			(at -7.050024 -2.54 270)
			(size 1.3208 3.0988)
			(layers "F.Cu" "F.Mask" "F.Paste")
			(net "P52V_HS2_GATE1")
		)
		(pad "S" smd rect
			(at -7.050024 2.54 270)
			(size 1.3208 3.0988)
			(layers "F.Cu" "F.Mask" "F.Paste")
			(net "P52V_HS2")
		)
		(zone
			(layer "F.Cu")
			(hatch none 0.5)
			(connect_pads
				(clearance 0)
			)
			(min_thickness 0.25)
			(keepout
				(tracks not_allowed)
				(vias allowed)
				(pads allowed)
				(copperpour not_allowed)
				(footprints allowed)
			)
			(placement
				(enabled no)
				(sheetname "")
			)
			(fill
				(thermal_gap 0.5)
				(thermal_bridge_width 0.5)
				(island_removal_mode 0)
			)
			(polygon
				(pts
					(xy 129.665476 -79.629) (xy 116.838476 -79.629) (xy 116.838476 -77.9018) (xy 119.048276 -77.9018)
					(xy 119.048276 -76.4794) (xy 116.838476 -76.4794) (xy 116.838476 -72.8218) (xy 119.048276 -72.8218)
					(xy 119.048276 -71.3994) (xy 116.838476 -71.3994) (xy 116.838476 -69.6722) (xy 129.665476 -69.6722)
					(xy 129.665476 -70.8406) (xy 123.467876 -70.8406) (xy 123.467876 -78.4606) (xy 129.665476 -78.4606)
				)
			)
		)
	)
	(footprint ""
		(layer "F.Cu")
		(at 185.928 -78.486 -90)
		(property "Reference" "C107"
			(at 0 0 270)
			(layer "F.SilkS")
			(hide yes)
			(effects
				(font
					(size 1.27 1.27)
				)
			)
		)
		(property "Value" ""
			(at 0 0 270)
			(layer "F.Fab")
			(effects
				(font
					(size 1.27 1.27)
				)
			)
		)
		(duplicate_pad_numbers_are_jumpers no)
		(fp_line
			(start -0.7874 0.4064)
			(end -0.7874 -0.4064)
			(stroke
				(width 0.1524)
				(type default)
			)
			(layer "F.SilkS")
		)
		(fp_line
			(start 0.7874 0.4064)
			(end -0.7874 0.4064)
			(stroke
				(width 0.1524)
				(type default)
			)
			(layer "F.SilkS")
		)
		(fp_line
			(start -0.7874 -0.4064)
			(end 0.7874 -0.4064)
			(stroke
				(width 0.1524)
				(type default)
			)
			(layer "F.SilkS")
		)
		(fp_line
			(start 0.7874 -0.4064)
			(end 0.7874 0.4064)
			(stroke
				(width 0.1524)
				(type default)
			)
			(layer "F.SilkS")
		)
		(fp_line
			(start -0.67945 0.3048)
			(end -0.67945 -0.305054)
			(stroke
				(width 0.1)
				(type default)
			)
			(layer "F.Fab")
		)
		(fp_line
			(start -0.12065 0.3048)
			(end -0.67945 0.3048)
			(stroke
				(width 0.1)
				(type default)
			)
			(layer "F.Fab")
		)
		(fp_line
			(start 0.120396 0.3048)
			(end 0.120396 0.2794)
			(stroke
				(width 0.1)
				(type default)
			)
			(layer "F.Fab")
		)
		(fp_line
			(start 0.67945 0.3048)
			(end 0.120396 0.3048)
			(stroke
				(width 0.1)
				(type default)
			)
			(layer "F.Fab")
		)
		(fp_line
			(start -0.12065 0.2794)
			(end -0.12065 0.3048)
			(stroke
				(width 0.1)
				(type default)
			)
			(layer "F.Fab")
		)
		(fp_line
			(start 0.120396 0.2794)
			(end -0.12065 0.2794)
			(stroke
				(width 0.1)
				(type default)
			)
			(layer "F.Fab")
		)
		(fp_line
			(start -0.12065 -0.2794)
			(end 0.12065 -0.2794)
			(stroke
				(width 0.1)
				(type default)
			)
			(layer "F.Fab")
		)
		(fp_line
			(start 0.12065 -0.2794)
			(end 0.12065 -0.3048)
			(stroke
				(width 0.1)
				(type default)
			)
			(layer "F.Fab")
		)
		(fp_line
			(start 0.12065 -0.3048)
			(end 0.67945 -0.3048)
			(stroke
				(width 0.1)
				(type default)
			)
			(layer "F.Fab")
		)
		(fp_line
			(start 0.67945 -0.3048)
			(end 0.67945 0.3048)
			(stroke
				(width 0.1)
				(type default)
			)
			(layer "F.Fab")
		)
		(fp_line
			(start -0.67945 -0.305054)
			(end -0.12065 -0.305054)
			(stroke
				(width 0.1)
				(type default)
			)
			(layer "F.Fab")
		)
		(fp_line
			(start -0.12065 -0.305054)
			(end -0.12065 -0.2794)
			(stroke
				(width 0.1)
				(type default)
			)
			(layer "F.Fab")
		)
		(pad "1" smd circle
			(at -0.40005 0 270)
			(size 0 0)
			(layers "F.Cu" "F.Mask" "F.Paste")
			(net "GND")
		)
		(pad "2" smd circle
			(at 0.40005 0 270)
			(size 0 0)
			(layers "F.Cu" "F.Mask" "F.Paste")
			(net "P3V3_AUX")
		)
	)
	(footprint ""
		(layer "F.Cu")
		(at 427.228 -45.974)
		(property "Reference" "R56"
			(at 0 0 0)
			(layer "F.SilkS")
			(hide yes)
			(effects
				(font
					(size 1.27 1.27)
				)
			)
		)
		(property "Value" ""
			(at 0 0 0)
			(layer "F.Fab")
			(effects
				(font
					(size 1.27 1.27)
				)
			)
		)
		(duplicate_pad_numbers_are_jumpers no)
		(fp_line
			(start -0.7874 -0.4064)
			(end 0.7874 -0.4064)
			(stroke
				(width 0.1524)
				(type default)
			)
			(layer "F.SilkS")
		)
		(fp_line
			(start -0.7874 0.4064)
			(end -0.7874 -0.4064)
			(stroke
				(width 0.1524)
				(type default)
			)
			(layer "F.SilkS")
		)
		(fp_line
			(start 0.7874 -0.4064)
			(end 0.7874 0.4064)
			(stroke
				(width 0.1524)
				(type default)
			)
			(layer "F.SilkS")
		)
		(fp_line
			(start 0.7874 0.4064)
			(end -0.7874 0.4064)
			(stroke
				(width 0.1524)
				(type default)
			)
			(layer "F.SilkS")
		)
		(fp_line
			(start -0.67945 -0.305054)
			(end -0.12065 -0.305054)
			(stroke
				(width 0.1)
				(type default)
			)
			(layer "F.Fab")
		)
		(fp_line
			(start -0.67945 0.3048)
			(end -0.67945 -0.305054)
			(stroke
				(width 0.1)
				(type default)
			)
			(layer "F.Fab")
		)
		(fp_line
			(start -0.12065 -0.305054)
			(end -0.12065 -0.2794)
			(stroke
				(width 0.1)
				(type default)
			)
			(layer "F.Fab")
		)
		(fp_line
			(start -0.12065 -0.2794)
			(end 0.12065 -0.2794)
			(stroke
				(width 0.1)
				(type default)
			)
			(layer "F.Fab")
		)
		(fp_line
			(start -0.12065 0.2794)
			(end -0.12065 0.3048)
			(stroke
				(width 0.1)
				(type default)
			)
			(layer "F.Fab")
		)
		(fp_line
			(start -0.12065 0.3048)
			(end -0.67945 0.3048)
			(stroke
				(width 0.1)
				(type default)
			)
			(layer "F.Fab")
		)
		(fp_line
			(start 0.120396 0.2794)
			(end -0.12065 0.2794)
			(stroke
				(width 0.1)
				(type default)
			)
			(layer "F.Fab")
		)
		(fp_line
			(start 0.120396 0.3048)
			(end 0.120396 0.2794)
			(stroke
				(width 0.1)
				(type default)
			)
			(layer "F.Fab")
		)
		(fp_line
			(start 0.12065 -0.3048)
			(end 0.67945 -0.3048)
			(stroke
				(width 0.1)
				(type default)
			)
			(layer "F.Fab")
		)
		(fp_line
			(start 0.12065 -0.2794)
			(end 0.12065 -0.3048)
			(stroke
				(width 0.1)
				(type default)
			)
			(layer "F.Fab")
		)
		(fp_line
			(start 0.67945 -0.3048)
			(end 0.67945 0.3048)
			(stroke
				(width 0.1)
				(type default)
			)
			(layer "F.Fab")
		)
		(fp_line
			(start 0.67945 0.3048)
			(end 0.120396 0.3048)
			(stroke
				(width 0.1)
				(type default)
			)
			(layer "F.Fab")
		)
		(pad "1" smd circle
			(at -0.40005 0)
			(size 0 0)
			(layers "F.Cu" "F.Mask" "F.Paste")
			(net "PCA9555_A0")
		)
		(pad "2" smd circle
			(at 0.40005 0)
			(size 0 0)
			(layers "F.Cu" "F.Mask" "F.Paste")
			(net "GND")
		)
	)
	(footprint ""
		(layer "F.Cu")
		(at 82.804 -17.907 90)
		(property "Reference" "R76"
			(at 0 0 90)
			(layer "F.SilkS")
			(hide yes)
			(effects
				(font
					(size 1.27 1.27)
				)
			)
		)
		(property "Value" ""
			(at 0 0 90)
			(layer "F.Fab")
			(effects
				(font
					(size 1.27 1.27)
				)
			)
		)
		(duplicate_pad_numbers_are_jumpers no)
		(fp_line
			(start 0.7874 -0.4064)
			(end 0.7874 0.4064)
			(stroke
				(width 0.1524)
				(type default)
			)
			(layer "F.SilkS")
		)
		(fp_line
			(start -0.7874 -0.4064)
			(end 0.7874 -0.4064)
			(stroke
				(width 0.1524)
				(type default)
			)
			(layer "F.SilkS")
		)
		(fp_line
			(start 0.7874 0.4064)
			(end -0.7874 0.4064)
			(stroke
				(width 0.1524)
				(type default)
			)
			(layer "F.SilkS")
		)
		(fp_line
			(start -0.7874 0.4064)
			(end -0.7874 -0.4064)
			(stroke
				(width 0.1524)
				(type default)
			)
			(layer "F.SilkS")
		)
		(fp_line
			(start -0.12065 -0.305054)
			(end -0.12065 -0.2794)
			(stroke
				(width 0.1)
				(type default)
			)
			(layer "F.Fab")
		)
		(fp_line
			(start -0.67945 -0.305054)
			(end -0.12065 -0.305054)
			(stroke
				(width 0.1)
				(type default)
			)
			(layer "F.Fab")
		)
		(fp_line
			(start 0.67945 -0.3048)
			(end 0.67945 0.3048)
			(stroke
				(width 0.1)
				(type default)
			)
			(layer "F.Fab")
		)
		(fp_line
			(start 0.12065 -0.3048)
			(end 0.67945 -0.3048)
			(stroke
				(width 0.1)
				(type default)
			)
			(layer "F.Fab")
		)
		(fp_line
			(start 0.12065 -0.2794)
			(end 0.12065 -0.3048)
			(stroke
				(width 0.1)
				(type default)
			)
			(layer "F.Fab")
		)
		(fp_line
			(start -0.12065 -0.2794)
			(end 0.12065 -0.2794)
			(stroke
				(width 0.1)
				(type default)
			)
			(layer "F.Fab")
		)
		(fp_line
			(start 0.120396 0.2794)
			(end -0.12065 0.2794)
			(stroke
				(width 0.1)
				(type default)
			)
			(layer "F.Fab")
		)
		(fp_line
			(start -0.12065 0.2794)
			(end -0.12065 0.3048)
			(stroke
				(width 0.1)
				(type default)
			)
			(layer "F.Fab")
		)
		(fp_line
			(start 0.67945 0.3048)
			(end 0.120396 0.3048)
			(stroke
				(width 0.1)
				(type default)
			)
			(layer "F.Fab")
		)
		(fp_line
			(start 0.120396 0.3048)
			(end 0.120396 0.2794)
			(stroke
				(width 0.1)
				(type default)
			)
			(layer "F.Fab")
		)
		(fp_line
			(start -0.12065 0.3048)
			(end -0.67945 0.3048)
			(stroke
				(width 0.1)
				(type default)
			)
			(layer "F.Fab")
		)
		(fp_line
			(start -0.67945 0.3048)
			(end -0.67945 -0.305054)
			(stroke
				(width 0.1)
				(type default)
			)
			(layer "F.Fab")
		)
		(pad "1" smd circle
			(at -0.40005 0 90)
			(size 0 0)
			(layers "F.Cu" "F.Mask" "F.Paste")
			(net "FAN_PWR_EN_1_R")
		)
		(pad "2" smd circle
			(at 0.40005 0 90)
			(size 0 0)
			(layers "F.Cu" "F.Mask" "F.Paste")
			(net "FAN_PWR_EN_BUF")
		)
	)
)
